(kicad_pcb
	(version 20260206)
	(generator "pcbnew")
	(generator_version "10.0")
	(general
		(thickness 1.6)
		(legacy_teardrops no)
	)
	(paper "A4")
	(title_block
		(title "Wiwynn_Tioga_Pass_MB.brd")
		(comment 1 "Tioga Pass / footprints 2032-2034 of 4770")
	)
	(layers
		(0 "F.Cu" signal "TOP")
		(4 "In1.Cu" signal "L2GND")
		(6 "In2.Cu" signal "L3")
		(8 "In3.Cu" signal "L4GND")
		(10 "In4.Cu" signal "L5")
		(12 "In5.Cu" signal "L6GND")
		(14 "In6.Cu" signal "L7VCC")
		(16 "In7.Cu" signal "L8VCC")
		(18 "In8.Cu" signal "L9GND")
		(20 "In9.Cu" signal "L10")
		(22 "In10.Cu" signal "L11GND")
		(24 "In11.Cu" signal "L12")
		(26 "In12.Cu" signal "L13GND")
		(2 "B.Cu" signal "BOTTOM")
		(9 "F.Adhes" user "F.Adhesive")
		(11 "B.Adhes" user "B.Adhesive")
		(13 "F.Paste" user "Package Geometry/Pastemask Top")
		(15 "B.Paste" user "Package Geometry/Pastemask Bottom")
		(5 "F.SilkS" user "Ref Des/Silkscreen Top")
		(7 "B.SilkS" user "Ref Des/Silkscreen Bottom")
		(1 "F.Mask" user "Board Geometry/Soldermask Top")
		(3 "B.Mask" user "Board Geometry/Soldermask Bottom")
		(17 "Dwgs.User" user "User.Drawings")
		(19 "Cmts.User" user "User.Comments")
		(21 "Eco1.User" user "User.Eco1")
		(23 "Eco2.User" user "User.Eco2")
		(25 "Edge.Cuts" user "Board Geometry/Outline")
		(27 "Margin" user)
		(31 "F.CrtYd" user "Package Geometry/Place Bound Top")
		(29 "B.CrtYd" user "Package Geometry/Place Bound Bottom")
		(35 "F.Fab" user "Ref Des/Assembly Top")
		(33 "B.Fab" user "Ref Des/Assembly Bottom")
	)
	(footprint ""
		(layer "F.Cu")
		(at 32.1564 -53.1368 -90)
		(property "Reference" "C1E8"
			(at 0 0 270)
			(layer "F.SilkS")
			(hide yes)
			(effects
				(font
					(size 1.27 1.27)
				)
			)
		)
		(property "Value" ""
			(at 0 0 270)
			(layer "F.Fab")
			(effects
				(font
					(size 1.27 1.27)
				)
			)
		)
		(duplicate_pad_numbers_are_jumpers no)
		(fp_rect
			(start 0.3048 0.9906)
			(end -0.3048 -0.1016)
			(stroke
				(width 0)
				(type default)
			)
			(fill no)
			(layer "F.CrtYd")
		)
		(fp_line
			(start -0.3048 0.9906)
			(end 0.3048 0.9906)
			(stroke
				(width 0.1)
				(type default)
			)
			(layer "F.Fab")
		)
		(fp_line
			(start 0.3048 0.9906)
			(end 0.3048 -0.1016)
			(stroke
				(width 0.1)
				(type default)
			)
			(layer "F.Fab")
		)
		(fp_line
			(start -0.3048 -0.1016)
			(end -0.3048 0.9906)
			(stroke
				(width 0.1)
				(type default)
			)
			(layer "F.Fab")
		)
		(fp_line
			(start 0.3048 -0.1016)
			(end -0.3048 -0.1016)
			(stroke
				(width 0.1)
				(type default)
			)
			(layer "F.Fab")
		)
		(pad "1" smd rect
			(at 0 0 270)
			(size 0.508 0.508)
			(layers "F.Cu" "F.Mask" "F.Paste")
			(net "VR_PVCCIN_CPU1_PH1_VCIN")
		)
		(pad "2" smd rect
			(at 0 0.889 270)
			(size 0.508 0.508)
			(layers "F.Cu" "F.Mask" "F.Paste")
			(net "GND")
		)
		(zone
			(layer "F.Cu")
			(hatch none 0.5)
			(connect_pads
				(clearance 0)
			)
			(min_thickness 0.25)
			(keepout
				(tracks not_allowed)
				(vias allowed)
				(pads allowed)
				(copperpour not_allowed)
				(footprints allowed)
			)
			(placement
				(enabled no)
				(sheetname "")
			)
			(fill
				(thermal_gap 0.5)
				(thermal_bridge_width 0.5)
				(island_removal_mode 0)
			)
			(polygon
				(pts
					(xy 31.5214 -52.8828) (xy 31.9024 -52.8828) (xy 31.9024 -53.3908) (xy 31.5214 -53.3908)
				)
			)
		)
		(zone
			(layer "F.Cu")
			(hatch none 0.5)
			(connect_pads
				(clearance 0)
			)
			(min_thickness 0.25)
			(keepout
				(tracks allowed)
				(vias not_allowed)
				(pads allowed)
				(copperpour not_allowed)
				(footprints allowed)
			)
			(placement
				(enabled no)
				(sheetname "")
			)
			(fill
				(thermal_gap 0.5)
				(thermal_bridge_width 0.5)
				(island_removal_mode 0)
			)
			(polygon
				(pts
					(xy 31.5214 -52.8828) (xy 31.9024 -52.8828) (xy 31.9024 -53.3908) (xy 31.5214 -53.3908)
				)
			)
		)
	)
	(footprint ""
		(layer "F.Cu")
		(at 177.994818 -51.051206 -90)
		(property "Reference" "C4E13"
			(at 0 0 270)
			(layer "F.SilkS")
			(hide yes)
			(effects
				(font
					(size 1.27 1.27)
				)
			)
		)
		(property "Value" ""
			(at 0 0 270)
			(layer "F.Fab")
			(effects
				(font
					(size 1.27 1.27)
				)
			)
		)
		(duplicate_pad_numbers_are_jumpers no)
		(fp_poly
			(pts
				(xy 0.3048 -0.1016) (xy 0.3048 0.9906) (xy -0.3048 0.9906) (xy -0.3048 -0.1016)
			)
			(stroke
				(width 0)
				(type default)
			)
			(fill no)
			(layer "F.CrtYd")
		)
		(fp_line
			(start -0.3048 0.9906)
			(end 0.3048 0.9906)
			(stroke
				(width 0.1)
				(type default)
			)
			(layer "F.Fab")
		)
		(fp_line
			(start 0.3048 0.9906)
			(end 0.3048 -0.1016)
			(stroke
				(width 0.1)
				(type default)
			)
			(layer "F.Fab")
		)
		(fp_line
			(start -0.3048 -0.1016)
			(end -0.3048 0.9906)
			(stroke
				(width 0.1)
				(type default)
			)
			(layer "F.Fab")
		)
		(fp_line
			(start 0.3048 -0.1016)
			(end -0.3048 -0.1016)
			(stroke
				(width 0.1)
				(type default)
			)
			(layer "F.Fab")
		)
		(pad "1" smd rect
			(at 0 0 270)
			(size 0.508 0.508)
			(layers "F.Cu" "F.Mask" "F.Paste")
			(net "VR_FET_SW_P12V_STBY_PVCCIN_CPU0")
		)
		(pad "2" smd rect
			(at 0 0.889 270)
			(size 0.508 0.508)
			(layers "F.Cu" "F.Mask" "F.Paste")
			(net "GND")
		)
		(zone
			(layer "F.Cu")
			(hatch none 0.5)
			(connect_pads
				(clearance 0)
			)
			(min_thickness 0.25)
			(keepout
				(tracks not_allowed)
				(vias allowed)
				(pads allowed)
				(copperpour not_allowed)
				(footprints allowed)
			)
			(placement
				(enabled no)
				(sheetname "")
			)
			(fill
				(thermal_gap 0.5)
				(thermal_bridge_width 0.5)
				(island_removal_mode 0)
			)
			(polygon
				(pts
					(xy 177.359818 -51.305206) (xy 177.359818 -50.797206) (xy 177.740818 -50.797206) (xy 177.740818 -51.305206)
				)
			)
		)
		(zone
			(layer "F.Cu")
			(hatch none 0.5)
			(connect_pads
				(clearance 0)
			)
			(min_thickness 0.25)
			(keepout
				(tracks allowed)
				(vias not_allowed)
				(pads allowed)
				(copperpour not_allowed)
				(footprints allowed)
			)
			(placement
				(enabled no)
				(sheetname "")
			)
			(fill
				(thermal_gap 0.5)
				(thermal_bridge_width 0.5)
				(island_removal_mode 0)
			)
			(polygon
				(pts
					(xy 177.740818 -51.305206) (xy 177.740818 -50.797206) (xy 177.359818 -50.797206) (xy 177.359818 -51.305206)
				)
			)
		)
	)
	(footprint ""
		(layer "F.Cu")
		(at 373.1006 -157.9118 -90)
		(property "Reference" "CT66"
			(at 5.79247 9.1694 0)
			(unlocked yes)
			(layer "F.SilkS")
			(effects
				(font
					(size 0.7874 0.5842)
					(thickness 0.1524)
				)
				(justify left)
			)
		)
		(property "Value" ""
			(at 0 0 270)
			(layer "F.Fab")
			(effects
				(font
					(size 1.27 1.27)
				)
			)
		)
		(duplicate_pad_numbers_are_jumpers no)
		(fp_poly
			(pts
				(xy 0.3048 -0.1016) (xy 0.3048 0.9906) (xy -0.3048 0.9906) (xy -0.3048 -0.1016)
			)
			(stroke
				(width 0)
				(type default)
			)
			(fill no)
			(layer "F.CrtYd")
		)
		(fp_line
			(start -0.3048 0.9906)
			(end 0.3048 0.9906)
			(stroke
				(width 0.1)
				(type default)
			)
			(layer "F.Fab")
		)
		(fp_line
			(start 0.3048 0.9906)
			(end 0.3048 -0.1016)
			(stroke
				(width 0.1)
				(type default)
			)
			(layer "F.Fab")
		)
		(fp_line
			(start -0.3048 -0.1016)
			(end -0.3048 0.9906)
			(stroke
				(width 0.1)
				(type default)
			)
			(layer "F.Fab")
		)
		(fp_line
			(start 0.3048 -0.1016)
			(end -0.3048 -0.1016)
			(stroke
				(width 0.1)
				(type default)
			)
			(layer "F.Fab")
		)
		(pad "1" smd rect
			(at 0 0 270)
			(size 0.508 0.508)
			(layers "F.Cu" "F.Mask" "F.Paste")
			(net "VR_PVNN_PCH_AIREF1")
		)
		(pad "2" smd rect
			(at 0 0.889 270)
			(size 0.508 0.508)
			(layers "F.Cu" "F.Mask" "F.Paste")
			(net "GND")
		)
		(zone
			(layer "F.Cu")
			(hatch none 0.5)
			(connect_pads
				(clearance 0)
			)
			(min_thickness 0.25)
			(keepout
				(tracks not_allowed)
				(vias allowed)
				(pads allowed)
				(copperpour not_allowed)
				(footprints allowed)
			)
			(placement
				(enabled no)
				(sheetname "")
			)
			(fill
				(thermal_gap 0.5)
				(thermal_bridge_width 0.5)
				(island_removal_mode 0)
			)
			(polygon
				(pts
					(xy 372.4656 -158.1658) (xy 372.4656 -157.6578) (xy 372.8466 -157.6578) (xy 372.8466 -158.1658)
				)
			)
		)
		(zone
			(layer "F.Cu")
			(hatch none 0.5)
			(connect_pads
				(clearance 0)
			)
			(min_thickness 0.25)
			(keepout
				(tracks allowed)
				(vias not_allowed)
				(pads allowed)
				(copperpour not_allowed)
				(footprints allowed)
			)
			(placement
				(enabled no)
				(sheetname "")
			)
			(fill
				(thermal_gap 0.5)
				(thermal_bridge_width 0.5)
				(island_removal_mode 0)
			)
			(polygon
				(pts
					(xy 372.8466 -158.1658) (xy 372.8466 -157.6578) (xy 372.4656 -157.6578) (xy 372.4656 -158.1658)
				)
			)
		)
	)
)
